# T6G (Grand Teton) — schematic netlist excerpt (pin names and nets, part order shuffled) for the footprints in the layout excerpt that follows; sources: Cadence DE-HDL packaged netlist, KiCad conversion of 04192023_DAF0TMB3IC0_F0TG_MB_C_brd_V02_OCP.brd

R3948  Q_RES  10K 1% CHIP  pkg 0402LF  page 147 : A = P3V3_AUX ; B = HP_LVC3_E1S_0_HSC_PWRGD
R350  Q_RES  33 5% CHIP  pkg 0402LF  page 151 : A = SMB_SCM_2_R2_SDA ; B = SMB_SCM_2_R5_SDA

(kicad_pcb
	(version 20260206)
	(generator "pcbnew")
	(generator_version "10.0")
	(general
		(thickness 1.6)
		(legacy_teardrops no)
	)
	(paper "A4")
	(title_block
		(title "04192023_DAF0TMB3IC0_F0TG_MB_C_brd_V02_OCP.brd")
		(comment 1 "Grand Teton / footprints 2774-2775 of 8354")
	)
	(layers
		(0 "F.Cu" signal "TOP")
		(4 "In1.Cu" signal "GND")
		(6 "In2.Cu" signal "IN1")
		(8 "In3.Cu" signal "GND1")
		(10 "In4.Cu" signal "IN2")
		(12 "In5.Cu" signal "GND2")
		(14 "In6.Cu" signal "IN3")
		(16 "In7.Cu" signal "GND3")
		(18 "In8.Cu" signal "VCC")
		(20 "In9.Cu" signal "VCC1")
		(22 "In10.Cu" signal "GND4")
		(24 "In11.Cu" signal "IN4")
		(26 "In12.Cu" signal "GND5")
		(28 "In13.Cu" signal "IN5")
		(30 "In14.Cu" signal "GND6")
		(32 "In15.Cu" signal "IN6")
		(34 "In16.Cu" signal "GND7")
		(2 "B.Cu" signal "BOTTOM")
		(9 "F.Adhes" user "F.Adhesive")
		(11 "B.Adhes" user "B.Adhesive")
		(13 "F.Paste" user "Package Geometry/Pastemask Top")
		(15 "B.Paste" user "Package Geometry/Pastemask Bottom")
		(5 "F.SilkS" user "Ref Des/Silkscreen Top")
		(7 "B.SilkS" user "Ref Des/Silkscreen Bottom")
		(1 "F.Mask" user "Board Geometry/Soldermask Top")
		(3 "B.Mask" user "Board Geometry/Soldermask Bottom")
		(17 "Dwgs.User" user "User.Drawings")
		(19 "Cmts.User" user "User.Comments")
		(21 "Eco1.User" user "User.Eco1")
		(23 "Eco2.User" user "User.Eco2")
		(25 "Edge.Cuts" user "Board Geometry/Outline")
		(27 "Margin" user)
		(31 "F.CrtYd" user "Package Geometry/Place Bound Top")
		(29 "B.CrtYd" user "Package Geometry/Place Bound Bottom")
		(35 "F.Fab" user "Ref Des/Assembly Top")
		(33 "B.Fab" user "Ref Des/Assembly Bottom")
	)
	(footprint ""
		(layer "F.Cu")
		(at 254.35433 -55.860442 -90)
		(property "Reference" "R3948"
			(at 0 0 270)
			(layer "F.SilkS")
			(hide yes)
			(effects
				(font
					(size 1.27 1.27)
				)
			)
		)
		(property "Value" ""
			(at 0 0 270)
			(layer "F.Fab")
			(effects
				(font
					(size 1.27 1.27)
				)
			)
		)
		(duplicate_pad_numbers_are_jumpers no)
		(fp_line
			(start -0.7874 0.4064)
			(end -0.7874 -0.4064)
			(stroke
				(width 0.1524)
				(type default)
			)
			(layer "F.SilkS")
		)
		(fp_line
			(start 0.7874 0.4064)
			(end -0.7874 0.4064)
			(stroke
				(width 0.1524)
				(type default)
			)
			(layer "F.SilkS")
		)
		(fp_line
			(start -0.7874 -0.4064)
			(end 0.7874 -0.4064)
			(stroke
				(width 0.1524)
				(type default)
			)
			(layer "F.SilkS")
		)
		(fp_line
			(start 0.7874 -0.4064)
			(end 0.7874 0.4064)
			(stroke
				(width 0.1524)
				(type default)
			)
			(layer "F.SilkS")
		)
		(fp_line
			(start -0.67945 0.3048)
			(end -0.67945 -0.305054)
			(stroke
				(width 0.1)
				(type default)
			)
			(layer "F.Fab")
		)
		(fp_line
			(start -0.12065 0.3048)
			(end -0.67945 0.3048)
			(stroke
				(width 0.1)
				(type default)
			)
			(layer "F.Fab")
		)
		(fp_line
			(start 0.120396 0.3048)
			(end 0.120396 0.2794)
			(stroke
				(width 0.1)
				(type default)
			)
			(layer "F.Fab")
		)
		(fp_line
			(start 0.67945 0.3048)
			(end 0.120396 0.3048)
			(stroke
				(width 0.1)
				(type default)
			)
			(layer "F.Fab")
		)
		(fp_line
			(start -0.12065 0.2794)
			(end -0.12065 0.3048)
			(stroke
				(width 0.1)
				(type default)
			)
			(layer "F.Fab")
		)
		(fp_line
			(start 0.120396 0.2794)
			(end -0.12065 0.2794)
			(stroke
				(width 0.1)
				(type default)
			)
			(layer "F.Fab")
		)
		(fp_line
			(start -0.12065 -0.2794)
			(end 0.12065 -0.2794)
			(stroke
				(width 0.1)
				(type default)
			)
			(layer "F.Fab")
		)
		(fp_line
			(start 0.12065 -0.2794)
			(end 0.12065 -0.3048)
			(stroke
				(width 0.1)
				(type default)
			)
			(layer "F.Fab")
		)
		(fp_line
			(start 0.12065 -0.3048)
			(end 0.67945 -0.3048)
			(stroke
				(width 0.1)
				(type default)
			)
			(layer "F.Fab")
		)
		(fp_line
			(start 0.67945 -0.3048)
			(end 0.67945 0.3048)
			(stroke
				(width 0.1)
				(type default)
			)
			(layer "F.Fab")
		)
		(fp_line
			(start -0.67945 -0.305054)
			(end -0.12065 -0.305054)
			(stroke
				(width 0.1)
				(type default)
			)
			(layer "F.Fab")
		)
		(fp_line
			(start -0.12065 -0.305054)
			(end -0.12065 -0.2794)
			(stroke
				(width 0.1)
				(type default)
			)
			(layer "F.Fab")
		)
		(pad "1" smd circle
			(at -0.40005 0 270)
			(size 0 0)
			(layers "F.Cu" "F.Mask" "F.Paste")
			(net "P3V3_AUX")
		)
		(pad "2" smd circle
			(at 0.40005 0 270)
			(size 0 0)
			(layers "F.Cu" "F.Mask" "F.Paste")
			(net "HP_LVC3_E1S_0_HSC_PWRGD")
		)
	)
	(footprint ""
		(layer "F.Cu")
		(at 161.29 -356.362 90)
		(property "Reference" "R350"
			(at 0 0 90)
			(layer "F.SilkS")
			(hide yes)
			(effects
				(font
					(size 1.27 1.27)
				)
			)
		)
		(property "Value" ""
			(at 0 0 90)
			(layer "F.Fab")
			(effects
				(font
					(size 1.27 1.27)
				)
			)
		)
		(duplicate_pad_numbers_are_jumpers no)
		(fp_line
			(start 0.7874 -0.4064)
			(end 0.7874 0.4064)
			(stroke
				(width 0.1524)
				(type default)
			)
			(layer "F.SilkS")
		)
		(fp_line
			(start -0.7874 -0.4064)
			(end 0.7874 -0.4064)
			(stroke
				(width 0.1524)
				(type default)
			)
			(layer "F.SilkS")
		)
		(fp_line
			(start 0.7874 0.4064)
			(end -0.7874 0.4064)
			(stroke
				(width 0.1524)
				(type default)
			)
			(layer "F.SilkS")
		)
		(fp_line
			(start -0.7874 0.4064)
			(end -0.7874 -0.4064)
			(stroke
				(width 0.1524)
				(type default)
			)
			(layer "F.SilkS")
		)
		(fp_line
			(start -0.12065 -0.305054)
			(end -0.12065 -0.2794)
			(stroke
				(width 0.1)
				(type default)
			)
			(layer "F.Fab")
		)
		(fp_line
			(start -0.67945 -0.305054)
			(end -0.12065 -0.305054)
			(stroke
				(width 0.1)
				(type default)
			)
			(layer "F.Fab")
		)
		(fp_line
			(start 0.67945 -0.3048)
			(end 0.67945 0.3048)
			(stroke
				(width 0.1)
				(type default)
			)
			(layer "F.Fab")
		)
		(fp_line
			(start 0.12065 -0.3048)
			(end 0.67945 -0.3048)
			(stroke
				(width 0.1)
				(type default)
			)
			(layer "F.Fab")
		)
		(fp_line
			(start 0.12065 -0.2794)
			(end 0.12065 -0.3048)
			(stroke
				(width 0.1)
				(type default)
			)
			(layer "F.Fab")
		)
		(fp_line
			(start -0.12065 -0.2794)
			(end 0.12065 -0.2794)
			(stroke
				(width 0.1)
				(type default)
			)
			(layer "F.Fab")
		)
		(fp_line
			(start 0.120396 0.2794)
			(end -0.12065 0.2794)
			(stroke
				(width 0.1)
				(type default)
			)
			(layer "F.Fab")
		)
		(fp_line
			(start -0.12065 0.2794)
			(end -0.12065 0.3048)
			(stroke
				(width 0.1)
				(type default)
			)
			(layer "F.Fab")
		)
		(fp_line
			(start 0.67945 0.3048)
			(end 0.120396 0.3048)
			(stroke
				(width 0.1)
				(type default)
			)
			(layer "F.Fab")
		)
		(fp_line
			(start 0.120396 0.3048)
			(end 0.120396 0.2794)
			(stroke
				(width 0.1)
				(type default)
			)
			(layer "F.Fab")
		)
		(fp_line
			(start -0.12065 0.3048)
			(end -0.67945 0.3048)
			(stroke
				(width 0.1)
				(type default)
			)
			(layer "F.Fab")
		)
		(fp_line
			(start -0.67945 0.3048)
			(end -0.67945 -0.305054)
			(stroke
				(width 0.1)
				(type default)
			)
			(layer "F.Fab")
		)
		(pad "1" smd circle
			(at -0.40005 0 90)
			(size 0 0)
			(layers "F.Cu" "F.Mask" "F.Paste")
			(net "SMB_SCM_2_R2_SDA")
		)
		(pad "2" smd circle
			(at 0.40005 0 90)
			(size 0 0)
			(layers "F.Cu" "F.Mask" "F.Paste")
			(net "SMB_SCM_2_R5_SDA")
		)
	)
)
